FILE_TYPE = MACRO_DRAWING;
SET COLOR_WIRE YELLOW;
SET COLOR_PROP ORANGE;
SET COLOR_DOT WHITE;
SET COLOR_ARC YELLOW;
SET COLOR_BODY GREEN;
SET COLOR_NOTE PURPLE;
SET PROP_DISPLAY VALUE;
SET PAGE_NUMBER P122;
FORCEADD QUANTA_TITLE_BLOCK_C..1
(0 0);
FORCEPROP 1 LAST CUSTOM_TXT_CDS <NAME_2>
J 0
(-3175 50);
FORCEPROP 1 LAST CUSTOM_TXT_CDS <NAME_1>
J 0
(-3175 175);
FORCEPROP 1 LAST CUSTOM_TXT_CDS <Q_NUMBER>
J 0
(-1403 103);
DISPLAY 1.212766 (-1403 103);
FORCEPROP 1 LAST CUSTOM_TXT_CDS <Q_PROJ>
J 0
(-2382 102);
DISPLAY 1.212766 (-2382 102);
FORCEPROP 1 LAST CUSTOM_TXT_CDS <Q_REV>
J 0
(-184 103);
DISPLAY 1.212766 (-184 103);
FORCEPROP 1 LAST CUSTOM_TXT_CDS <CON_LAST_MODIFIED>
J 0
(-1885 15);
DISPLAY 0.978723 (-1885 15);
FORCEPROP 1 LAST CUSTOM_TXT_CDS <CON_PAGE_NUM> OF <CON_TOTAL_PAGES>
J 0
(-446 18);
DISPLAY 0.978723 (-446 18);
FORCEPROP 1 LAST Q_DEPT BU9
J 1
(-3763 49);
DISPLAY 1.957447 (-3763 49);
PAINT GREEN (-3763 49);
FORCEPROP 1 LAST Q_TITLE OCP 3.0 - SIDEBAND
J 0
(-9325 50);
DISPLAY 2.446809 (-9325 50);
PAINT GREEN (-9325 50);
FORCEPROP 2 LAST CDS_LIB pure_quanta
J 0
(0 0);
DISPLAY INVISIBLE (0 0);
FORCEPROP 1 LAST CDS_LMAN_SYM_OUTLINE -9475,6775,100,-125
J 0
(0 0);
DISPLAY 0.468085 (0 0);
PAINT GREEN (0 0);
DISPLAY INVISIBLE (0 0);
FORCEPROP 2 LAST PAGE_BORDER TRUE
J 0
(-7890 5250);
DISPLAY 0.638298 (-7890 5250);
PAINT PINK (-7890 5250);
DISPLAY INVISIBLE (-7890 5250);
FORCEPROP 1 LAST COMMENT_BODY TRUE
J 0
(12 -13);
DISPLAY 0.978723 (12 -13);
PAINT GREEN (12 -13);
DISPLAY INVISIBLE (12 -13);
FORCEPROP 2 LAST CDS_XR_PAGE_TITLE CR-122 : @T6G_MB_LIB.T6G(SCH_1):PAGE122
J 0
(-7890 5250);
DISPLAY 0.638298 (-7890 5250);
PAINT PINK (-7890 5250);
DISPLAY INVISIBLE (-7890 5250);
FORCEPROP 2 LAST CUSTOM_TXT_CDS <XR_PAGE_TITLE>
J 0
(-7890 5250);
DISPLAY 0.638298 (-7890 5250);
PAINT PINK (-7890 5250);
DISPLAY INVISIBLE (-7890 5250);
FORCEPROP 0 LAST CDS_CON_LAST_MODIFIED Wed Mar 09 17:54:35 2022
J 0
(-1885 15);
DISPLAY INVISIBLE (-1885 15);
QUIT
